# SCM (Grand Teton) — schematic netlist excerpt (pin names and nets, part order shuffled) for the footprints in the layout excerpt that follows; sources: Cadence DE-HDL packaged netlist, KiCad conversion of 12092022_DA0F0TMDCD0_F0T_Management_Board_D_brd_V3_OCP.brd

R529  Q_RES  100 1% CHIP  pkg 0402LF  page 52 : A = PWRGD_P1V8_AUX ; B = PWRGD_P1V8_AUX_R2
PC255  Q_CAP  0.1UF 25V 10% X7R  pkg 0402  page 55 : A = P1V2_AUX ; B = GND

(kicad_pcb
	(version 20260206)
	(generator "pcbnew")
	(generator_version "10.0")
	(general
		(thickness 1.6)
		(legacy_teardrops no)
	)
	(paper "A4")
	(title_block
		(title "12092022_DA0F0TMDCD0_F0T_Management_Board_D_brd_V3_OCP.brd")
		(comment 1 "Grand Teton / footprints 465-466 of 1440")
	)
	(layers
		(0 "F.Cu" signal "TOP")
		(4 "In1.Cu" signal "GND")
		(6 "In2.Cu" signal "IN1")
		(8 "In3.Cu" signal "GND1")
		(10 "In4.Cu" signal "IN2")
		(12 "In5.Cu" signal "VCC")
		(14 "In6.Cu" signal "VCC1")
		(16 "In7.Cu" signal "IN3")
		(18 "In8.Cu" signal "GND2")
		(20 "In9.Cu" signal "IN4")
		(22 "In10.Cu" signal "GND3")
		(2 "B.Cu" signal "BOTTOM")
		(9 "F.Adhes" user "F.Adhesive")
		(11 "B.Adhes" user "B.Adhesive")
		(13 "F.Paste" user "Package Geometry/Pastemask Top")
		(15 "B.Paste" user "Package Geometry/Pastemask Bottom")
		(5 "F.SilkS" user "Ref Des/Silkscreen Top")
		(7 "B.SilkS" user "Ref Des/Silkscreen Bottom")
		(1 "F.Mask" user "Board Geometry/Soldermask Top")
		(3 "B.Mask" user "Board Geometry/Soldermask Bottom")
		(17 "Dwgs.User" user "User.Drawings")
		(19 "Cmts.User" user "User.Comments")
		(21 "Eco1.User" user "User.Eco1")
		(23 "Eco2.User" user "User.Eco2")
		(25 "Edge.Cuts" user "Board Geometry/Outline")
		(27 "Margin" user)
		(31 "F.CrtYd" user "Package Geometry/Place Bound Top")
		(29 "B.CrtYd" user "Package Geometry/Place Bound Bottom")
		(35 "F.Fab" user "Ref Des/Assembly Top")
		(33 "B.Fab" user "Ref Des/Assembly Bottom")
	)
	(footprint ""
		(layer "F.Cu")
		(at 13.5636 -56.0324)
		(property "Reference" "R529"
			(at 0 0 0)
			(layer "F.SilkS")
			(hide yes)
			(effects
				(font
					(size 1.27 1.27)
				)
			)
		)
		(property "Value" ""
			(at 0 0 0)
			(layer "F.Fab")
			(effects
				(font
					(size 1.27 1.27)
				)
			)
		)
		(duplicate_pad_numbers_are_jumpers no)
		(fp_line
			(start -0.7874 -0.4064)
			(end 0.7874 -0.4064)
			(stroke
				(width 0.1524)
				(type default)
			)
			(layer "F.SilkS")
		)
		(fp_line
			(start -0.7874 0.4064)
			(end -0.7874 -0.4064)
			(stroke
				(width 0.1524)
				(type default)
			)
			(layer "F.SilkS")
		)
		(fp_line
			(start 0.7874 -0.4064)
			(end 0.7874 0.4064)
			(stroke
				(width 0.1524)
				(type default)
			)
			(layer "F.SilkS")
		)
		(fp_line
			(start 0.7874 0.4064)
			(end -0.7874 0.4064)
			(stroke
				(width 0.1524)
				(type default)
			)
			(layer "F.SilkS")
		)
		(fp_line
			(start -0.67945 -0.305054)
			(end -0.12065 -0.305054)
			(stroke
				(width 0.1)
				(type default)
			)
			(layer "F.Fab")
		)
		(fp_line
			(start -0.67945 0.3048)
			(end -0.67945 -0.305054)
			(stroke
				(width 0.1)
				(type default)
			)
			(layer "F.Fab")
		)
		(fp_line
			(start -0.12065 -0.305054)
			(end -0.12065 -0.2794)
			(stroke
				(width 0.1)
				(type default)
			)
			(layer "F.Fab")
		)
		(fp_line
			(start -0.12065 -0.2794)
			(end 0.12065 -0.2794)
			(stroke
				(width 0.1)
				(type default)
			)
			(layer "F.Fab")
		)
		(fp_line
			(start -0.12065 0.2794)
			(end -0.12065 0.3048)
			(stroke
				(width 0.1)
				(type default)
			)
			(layer "F.Fab")
		)
		(fp_line
			(start -0.12065 0.3048)
			(end -0.67945 0.3048)
			(stroke
				(width 0.1)
				(type default)
			)
			(layer "F.Fab")
		)
		(fp_line
			(start 0.120396 0.2794)
			(end -0.12065 0.2794)
			(stroke
				(width 0.1)
				(type default)
			)
			(layer "F.Fab")
		)
		(fp_line
			(start 0.120396 0.3048)
			(end 0.120396 0.2794)
			(stroke
				(width 0.1)
				(type default)
			)
			(layer "F.Fab")
		)
		(fp_line
			(start 0.12065 -0.3048)
			(end 0.67945 -0.3048)
			(stroke
				(width 0.1)
				(type default)
			)
			(layer "F.Fab")
		)
		(fp_line
			(start 0.12065 -0.2794)
			(end 0.12065 -0.3048)
			(stroke
				(width 0.1)
				(type default)
			)
			(layer "F.Fab")
		)
		(fp_line
			(start 0.67945 -0.3048)
			(end 0.67945 0.3048)
			(stroke
				(width 0.1)
				(type default)
			)
			(layer "F.Fab")
		)
		(fp_line
			(start 0.67945 0.3048)
			(end 0.120396 0.3048)
			(stroke
				(width 0.1)
				(type default)
			)
			(layer "F.Fab")
		)
		(pad "1" smd circle
			(at -0.40005 0)
			(size 0 0)
			(layers "F.Cu" "F.Mask" "F.Paste")
			(net "PWRGD_P1V8_AUX")
		)
		(pad "2" smd circle
			(at 0.40005 0)
			(size 0 0)
			(layers "F.Cu" "F.Mask" "F.Paste")
			(net "PWRGD_P1V8_AUX_R2")
		)
	)
	(footprint ""
		(layer "F.Cu")
		(at 85.654642 -58.942478 -90)
		(property "Reference" "PC255"
			(at 0 0 270)
			(layer "F.SilkS")
			(hide yes)
			(effects
				(font
					(size 1.27 1.27)
				)
			)
		)
		(property "Value" ""
			(at 0 0 270)
			(layer "F.Fab")
			(effects
				(font
					(size 1.27 1.27)
				)
			)
		)
		(duplicate_pad_numbers_are_jumpers no)
		(fp_line
			(start -0.7874 0.4064)
			(end -0.7874 -0.4064)
			(stroke
				(width 0.1524)
				(type default)
			)
			(layer "F.SilkS")
		)
		(fp_line
			(start 0.7874 0.4064)
			(end -0.7874 0.4064)
			(stroke
				(width 0.1524)
				(type default)
			)
			(layer "F.SilkS")
		)
		(fp_line
			(start -0.7874 -0.4064)
			(end 0.7874 -0.4064)
			(stroke
				(width 0.1524)
				(type default)
			)
			(layer "F.SilkS")
		)
		(fp_line
			(start 0.7874 -0.4064)
			(end 0.7874 0.4064)
			(stroke
				(width 0.1524)
				(type default)
			)
			(layer "F.SilkS")
		)
		(fp_line
			(start -0.67945 0.3048)
			(end -0.67945 -0.305054)
			(stroke
				(width 0.1)
				(type default)
			)
			(layer "F.Fab")
		)
		(fp_line
			(start -0.12065 0.3048)
			(end -0.67945 0.3048)
			(stroke
				(width 0.1)
				(type default)
			)
			(layer "F.Fab")
		)
		(fp_line
			(start 0.120396 0.3048)
			(end 0.120396 0.2794)
			(stroke
				(width 0.1)
				(type default)
			)
			(layer "F.Fab")
		)
		(fp_line
			(start 0.67945 0.3048)
			(end 0.120396 0.3048)
			(stroke
				(width 0.1)
				(type default)
			)
			(layer "F.Fab")
		)
		(fp_line
			(start -0.12065 0.2794)
			(end -0.12065 0.3048)
			(stroke
				(width 0.1)
				(type default)
			)
			(layer "F.Fab")
		)
		(fp_line
			(start 0.120396 0.2794)
			(end -0.12065 0.2794)
			(stroke
				(width 0.1)
				(type default)
			)
			(layer "F.Fab")
		)
		(fp_line
			(start -0.12065 -0.2794)
			(end 0.12065 -0.2794)
			(stroke
				(width 0.1)
				(type default)
			)
			(layer "F.Fab")
		)
		(fp_line
			(start 0.12065 -0.2794)
			(end 0.12065 -0.3048)
			(stroke
				(width 0.1)
				(type default)
			)
			(layer "F.Fab")
		)
		(fp_line
			(start 0.12065 -0.3048)
			(end 0.67945 -0.3048)
			(stroke
				(width 0.1)
				(type default)
			)
			(layer "F.Fab")
		)
		(fp_line
			(start 0.67945 -0.3048)
			(end 0.67945 0.3048)
			(stroke
				(width 0.1)
				(type default)
			)
			(layer "F.Fab")
		)
		(fp_line
			(start -0.67945 -0.305054)
			(end -0.12065 -0.305054)
			(stroke
				(width 0.1)
				(type default)
			)
			(layer "F.Fab")
		)
		(fp_line
			(start -0.12065 -0.305054)
			(end -0.12065 -0.2794)
			(stroke
				(width 0.1)
				(type default)
			)
			(layer "F.Fab")
		)
		(pad "1" smd circle
			(at -0.40005 0 270)
			(size 0 0)
			(layers "F.Cu" "F.Mask" "F.Paste")
			(net "P1V2_AUX")
		)
		(pad "2" smd circle
			(at 0.40005 0 270)
			(size 0 0)
			(layers "F.Cu" "F.Mask" "F.Paste")
			(net "GND")
		)
	)
)
